(kicad_pcb
	(version 20260206)
	(generator "pcbnew")
	(generator_version "10.0")
	(general
		(thickness 1.6)
		(legacy_teardrops no)
	)
	(paper "A4")
	(title_block
		(title "01162023_DA0F0TEBIF0_F0T_Expander_BD_F_brd_V02_OCP.brd")
		(comment 1 "Grand Teton / footprint 5834 of 9728 (J23), pads 110-179 of 179")
	)
	(layers
		(0 "F.Cu" signal "TOP")
		(4 "In1.Cu" signal "GND")
		(6 "In2.Cu" signal "VCC")
		(8 "In3.Cu" signal "VCC1")
		(10 "In4.Cu" signal "GND1")
		(12 "In5.Cu" signal "IN1")
		(14 "In6.Cu" signal "GND2")
		(16 "In7.Cu" signal "IN2")
		(18 "In8.Cu" signal "GND3")
		(20 "In9.Cu" signal "IN3")
		(22 "In10.Cu" signal "GND4")
		(24 "In11.Cu" signal "IN4")
		(26 "In12.Cu" signal "GND5")
		(28 "In13.Cu" signal "IN5")
		(30 "In14.Cu" signal "GND6")
		(32 "In15.Cu" signal "IN6")
		(34 "In16.Cu" signal "GND7")
		(2 "B.Cu" signal "BOTTOM")
		(9 "F.Adhes" user "F.Adhesive")
		(11 "B.Adhes" user "B.Adhesive")
		(13 "F.Paste" user "Package Geometry/Pastemask Top")
		(15 "B.Paste" user "Package Geometry/Pastemask Bottom")
		(5 "F.SilkS" user "Ref Des/Silkscreen Top")
		(7 "B.SilkS" user "Ref Des/Silkscreen Bottom")
		(1 "F.Mask" user "Board Geometry/Soldermask Top")
		(3 "B.Mask" user "Board Geometry/Soldermask Bottom")
		(17 "Dwgs.User" user "User.Drawings")
		(19 "Cmts.User" user "User.Comments")
		(21 "Eco1.User" user "User.Eco1")
		(23 "Eco2.User" user "User.Eco2")
		(25 "Edge.Cuts" user "Board Geometry/Outline")
		(27 "Margin" user)
		(31 "F.CrtYd" user "Package Geometry/Place Bound Top")
		(29 "B.CrtYd" user "Package Geometry/Place Bound Bottom")
		(35 "F.Fab" user "Ref Des/Assembly Top")
		(33 "B.Fab" user "Ref Des/Assembly Bottom")
	)
	(footprint ""
		(layer "F.Cu")
		(at 188.079888 -127.700024 180)
		(property "Reference" "J23"
			(at 5.351018 -34.634424 90)
			(unlocked yes)
			(layer "F.SilkS")
			(effects
				(font
					(size 0.7874 0.5842)
					(thickness 0.1524)
				)
				(justify left)
			)
		)
		(property "Value" ""
			(at 0 0 180)
			(layer "F.Fab")
			(effects
				(font
					(size 1.27 1.27)
				)
			)
		)
		(duplicate_pad_numbers_are_jumpers no)
		(pad "B38" smd rect
			(at -1.27762 7.14502 90)
			(size 0.3556 1.2192)
			(layers "F.Cu" "F.Mask" "F.Paste")
			(net "GND")
		)
		(pad "B39" smd rect
			(at -1.27762 7.744968 90)
			(size 0.3556 1.2192)
			(layers "F.Cu" "F.Mask" "F.Paste")
			(net "P5E_PEX1_STN0_TX_C_DN<7>")
		)
		(pad "B40" smd rect
			(at -1.27762 8.344916 90)
			(size 0.3556 1.2192)
			(layers "F.Cu" "F.Mask" "F.Paste")
			(net "P5E_PEX1_STN0_TX_C_DP<7>")
		)
		(pad "B41" smd rect
			(at -1.27762 8.945118 90)
			(size 0.3556 1.2192)
			(layers "F.Cu" "F.Mask" "F.Paste")
			(net "GND")
		)
		(pad "B42" smd rect
			(at -1.27762 9.545066 90)
			(size 0.3556 1.2192)
			(layers "F.Cu" "F.Mask" "F.Paste")
			(net "PRSNTB0_NIC3_N")
		)
		(pad "B43" smd rect
			(at -1.27762 14.454886 90)
			(size 0.3556 1.2192)
			(layers "F.Cu" "F.Mask" "F.Paste")
			(net "GND")
		)
		(pad "B44" smd rect
			(at -1.27762 15.055088 90)
			(size 0.3556 1.2192)
			(layers "F.Cu" "F.Mask" "F.Paste")
			(net "P5E_PEX1_STN0_TX_C_DN<8>")
		)
		(pad "B45" smd rect
			(at -1.27762 15.655036 90)
			(size 0.3556 1.2192)
			(layers "F.Cu" "F.Mask" "F.Paste")
			(net "P5E_PEX1_STN0_TX_C_DP<8>")
		)
		(pad "B46" smd rect
			(at -1.27762 16.254984 90)
			(size 0.3556 1.2192)
			(layers "F.Cu" "F.Mask" "F.Paste")
			(net "GND")
		)
		(pad "B47" smd rect
			(at -1.27762 16.854932 90)
			(size 0.3556 1.2192)
			(layers "F.Cu" "F.Mask" "F.Paste")
			(net "P5E_PEX1_STN0_TX_C_DN<9>")
		)
		(pad "B48" smd rect
			(at -1.27762 17.45488 90)
			(size 0.3556 1.2192)
			(layers "F.Cu" "F.Mask" "F.Paste")
			(net "P5E_PEX1_STN0_TX_C_DP<9>")
		)
		(pad "B49" smd rect
			(at -1.27762 18.055082 90)
			(size 0.3556 1.2192)
			(layers "F.Cu" "F.Mask" "F.Paste")
			(net "GND")
		)
		(pad "B50" smd rect
			(at -1.27762 18.65503 90)
			(size 0.3556 1.2192)
			(layers "F.Cu" "F.Mask" "F.Paste")
			(net "P5E_PEX1_STN0_TX_C_DN<10>")
		)
		(pad "B51" smd rect
			(at -1.27762 19.254978 90)
			(size 0.3556 1.2192)
			(layers "F.Cu" "F.Mask" "F.Paste")
			(net "P5E_PEX1_STN0_TX_C_DP<10>")
		)
		(pad "B52" smd rect
			(at -1.27762 19.854926 90)
			(size 0.3556 1.2192)
			(layers "F.Cu" "F.Mask" "F.Paste")
			(net "GND")
		)
		(pad "B53" smd rect
			(at -1.27762 20.455128 90)
			(size 0.3556 1.2192)
			(layers "F.Cu" "F.Mask" "F.Paste")
			(net "P5E_PEX1_STN0_TX_C_DN<11>")
		)
		(pad "B54" smd rect
			(at -1.27762 21.055076 90)
			(size 0.3556 1.2192)
			(layers "F.Cu" "F.Mask" "F.Paste")
			(net "P5E_PEX1_STN0_TX_C_DP<11>")
		)
		(pad "B55" smd rect
			(at -1.27762 21.655024 90)
			(size 0.3556 1.2192)
			(layers "F.Cu" "F.Mask" "F.Paste")
			(net "GND")
		)
		(pad "B56" smd rect
			(at -1.27762 22.254972 90)
			(size 0.3556 1.2192)
			(layers "F.Cu" "F.Mask" "F.Paste")
			(net "P5E_PEX1_STN0_TX_C_DP<12>")
		)
		(pad "B57" smd rect
			(at -1.27762 22.85492 90)
			(size 0.3556 1.2192)
			(layers "F.Cu" "F.Mask" "F.Paste")
			(net "P5E_PEX1_STN0_TX_C_DN<12>")
		)
		(pad "B58" smd rect
			(at -1.27762 23.455122 90)
			(size 0.3556 1.2192)
			(layers "F.Cu" "F.Mask" "F.Paste")
			(net "GND")
		)
		(pad "B59" smd rect
			(at -1.27762 24.05507 90)
			(size 0.3556 1.2192)
			(layers "F.Cu" "F.Mask" "F.Paste")
			(net "P5E_PEX1_STN0_TX_C_DN<13>")
		)
		(pad "B60" smd rect
			(at -1.27762 24.655018 90)
			(size 0.3556 1.2192)
			(layers "F.Cu" "F.Mask" "F.Paste")
			(net "P5E_PEX1_STN0_TX_C_DP<13>")
		)
		(pad "B61" smd rect
			(at -1.27762 25.254966 90)
			(size 0.3556 1.2192)
			(layers "F.Cu" "F.Mask" "F.Paste")
			(net "GND")
		)
		(pad "B62" smd rect
			(at -1.27762 25.854914 90)
			(size 0.3556 1.2192)
			(layers "F.Cu" "F.Mask" "F.Paste")
			(net "P5E_PEX1_STN0_TX_C_DP<14>")
		)
		(pad "B63" smd rect
			(at -1.27762 26.455116 90)
			(size 0.3556 1.2192)
			(layers "F.Cu" "F.Mask" "F.Paste")
			(net "P5E_PEX1_STN0_TX_C_DN<14>")
		)
		(pad "B64" smd rect
			(at -1.27762 27.055064 90)
			(size 0.3556 1.2192)
			(layers "F.Cu" "F.Mask" "F.Paste")
			(net "GND")
		)
		(pad "B65" smd rect
			(at -1.27762 27.655012 90)
			(size 0.3556 1.2192)
			(layers "F.Cu" "F.Mask" "F.Paste")
			(net "P5E_PEX1_STN0_TX_C_DN<15>")
		)
		(pad "B66" smd rect
			(at -1.27762 28.25496 90)
			(size 0.3556 1.2192)
			(layers "F.Cu" "F.Mask" "F.Paste")
			(net "P5E_PEX1_STN0_TX_C_DP<15>")
		)
		(pad "B67" smd rect
			(at -1.27762 28.854908 90)
			(size 0.3556 1.2192)
			(layers "F.Cu" "F.Mask" "F.Paste")
			(net "GND")
		)
		(pad "B68" smd rect
			(at -1.27762 29.45511 90)
			(size 0.3556 1.2192)
			(layers "F.Cu" "F.Mask" "F.Paste")
			(net "Net_2620")
		)
		(pad "B69" smd rect
			(at -1.27762 30.055058 90)
			(size 0.3556 1.2192)
			(layers "F.Cu" "F.Mask" "F.Paste")
			(net "Net_2621")
		)
		(pad "B70" smd rect
			(at -1.27762 30.655006 90)
			(size 0.3556 1.2192)
			(layers "F.Cu" "F.Mask" "F.Paste")
			(net "PRSNTB3_NIC3_N")
		)
		(pad "G1" thru_hole oval
			(at 1.022604 -34.034984 90)
			(size 1.6256 3.4798)
			(drill oval 1.1176 2.4638)
			(layers "*.Cu" "*.Mask")
			(remove_unused_layers no)
			(net "GND")
			(clearance 0.127)
			(thermal_gap 0.127)
		)
		(pad "G2" thru_hole oval
			(at 1.022604 -20.625054 90)
			(size 1.6256 3.4798)
			(drill oval 1.1176 2.4638)
			(layers "*.Cu" "*.Mask")
			(remove_unused_layers no)
			(net "GND")
			(clearance 0.127)
			(thermal_gap 0.127)
		)
		(pad "G3" thru_hole oval
			(at 1.022604 -0.255016 90)
			(size 1.6256 3.4798)
			(drill oval 1.1176 2.4638)
			(layers "*.Cu" "*.Mask")
			(remove_unused_layers no)
			(net "GND")
			(clearance 0.127)
			(thermal_gap 0.127)
		)
		(pad "G4" thru_hole oval
			(at 1.022604 12.005056 90)
			(size 1.6256 3.4798)
			(drill oval 1.1176 2.4638)
			(layers "*.Cu" "*.Mask")
			(remove_unused_layers no)
			(net "GND")
			(clearance 0.127)
			(thermal_gap 0.127)
		)
		(pad "G5" thru_hole oval
			(at 1.022604 34.034984 90)
			(size 1.5748 3.4798)
			(drill oval 1.1176 2.4638)
			(layers "*.Cu" "*.Mask")
			(remove_unused_layers no)
			(net "GND")
			(clearance 0.1524)
			(thermal_gap 0.1524)
		)
		(pad "G6" thru_hole circle
			(at -3.16738 -20.625054 180)
			(size 1.6256 1.6256)
			(drill 1.1176)
			(layers "*.Cu" "*.Mask")
			(remove_unused_layers no)
			(net "GND")
			(clearance 0)
		)
		(pad "G7" thru_hole circle
			(at -3.16738 12.005056 180)
			(size 1.6256 1.6256)
			(drill 1.1176)
			(layers "*.Cu" "*.Mask")
			(remove_unused_layers no)
			(net "GND")
			(clearance 0)
		)
		(pad "G8" thru_hole circle
			(at 4.20243 -20.625054 180)
			(size 1.6256 1.6256)
			(drill 1.1176)
			(layers "*.Cu" "*.Mask")
			(remove_unused_layers no)
			(net "GND")
			(clearance 0)
		)
		(pad "G9" thru_hole circle
			(at 4.20243 12.005056 180)
			(size 1.6256 1.6256)
			(drill 1.1176)
			(layers "*.Cu" "*.Mask")
			(remove_unused_layers no)
			(net "GND")
			(clearance 0)
		)
		(pad "OA1" smd rect
			(at 3.322574 -30.660086 90)
			(size 0.3556 1.2192)
			(layers "F.Cu" "F.Mask" "F.Paste")
			(net "RST_NIC3_PERST2_R_N")
		)
		(pad "OA2" smd rect
			(at 3.322574 -30.059884 90)
			(size 0.3556 1.2192)
			(layers "F.Cu" "F.Mask" "F.Paste")
			(net "RST_NIC3_PERST3_R_N")
		)
		(pad "OA3" smd rect
			(at 3.322574 -29.459936 90)
			(size 0.3556 1.2192)
			(layers "F.Cu" "F.Mask" "F.Paste")
			(net "Net_2624")
		)
		(pad "OA4" smd rect
			(at 3.322574 -28.859988 90)
			(size 0.3556 1.2192)
			(layers "F.Cu" "F.Mask" "F.Paste")
			(net "NIC3_RBT_ARB_IN")
		)
		(pad "OA5" smd rect
			(at 3.322574 -28.26004 90)
			(size 0.3556 1.2192)
			(layers "F.Cu" "F.Mask" "F.Paste")
			(net "NIC3_RBT_ARB_OUT")
		)
		(pad "OA6" smd rect
			(at 3.322574 -27.660092 90)
			(size 0.3556 1.2192)
			(layers "F.Cu" "F.Mask" "F.Paste")
			(net "NIC3_SLOT_ID1")
		)
		(pad "OA7" smd rect
			(at 3.322574 -27.05989 90)
			(size 0.3556 1.2192)
			(layers "F.Cu" "F.Mask" "F.Paste")
			(net "NCSI_NIC3_TX_EN")
		)
		(pad "OA8" smd rect
			(at 3.322574 -26.459942 90)
			(size 0.3556 1.2192)
			(layers "F.Cu" "F.Mask" "F.Paste")
			(net "NCSI_NIC3_TXD1")
		)
		(pad "OA9" smd rect
			(at 3.322574 -25.859994 90)
			(size 0.3556 1.2192)
			(layers "F.Cu" "F.Mask" "F.Paste")
			(net "NCSI_NIC3_TXD0")
		)
		(pad "OA10" smd rect
			(at 3.322574 -25.260046 90)
			(size 0.3556 1.2192)
			(layers "F.Cu" "F.Mask" "F.Paste")
			(net "GND")
		)
		(pad "OA11" smd rect
			(at 3.322574 -24.660098 90)
			(size 0.3556 1.2192)
			(layers "F.Cu" "F.Mask" "F.Paste")
			(net "Net_2616")
		)
		(pad "OA12" smd rect
			(at 3.322574 -24.059896 90)
			(size 0.3556 1.2192)
			(layers "F.Cu" "F.Mask" "F.Paste")
			(net "Net_2619")
		)
		(pad "OA13" smd rect
			(at 3.322574 -23.459948 90)
			(size 0.3556 1.2192)
			(layers "F.Cu" "F.Mask" "F.Paste")
			(net "GND")
		)
		(pad "OA14" smd rect
			(at 3.322574 -22.86 90)
			(size 0.3556 1.2192)
			(layers "F.Cu" "F.Mask" "F.Paste")
			(net "CLK_50M_NIC3_RBT_REF")
		)
		(pad "OB1" smd rect
			(at -1.27762 -30.660086 90)
			(size 0.3556 1.2192)
			(layers "F.Cu" "F.Mask" "F.Paste")
			(net "PWRGD_NIC3_PWR_GOOD")
		)
		(pad "OB2" smd rect
			(at -1.27762 -30.059884 90)
			(size 0.3556 1.2192)
			(layers "F.Cu" "F.Mask" "F.Paste")
			(net "NIC3_MAIN_PWR_EN_R")
		)
		(pad "OB3" smd rect
			(at -1.27762 -29.459936 90)
			(size 0.3556 1.2192)
			(layers "F.Cu" "F.Mask" "F.Paste")
			(net "NIC3_LD_N")
		)
		(pad "OB4" smd rect
			(at -1.27762 -28.859988 90)
			(size 0.3556 1.2192)
			(layers "F.Cu" "F.Mask" "F.Paste")
			(net "NIC3_DATA_IN")
		)
		(pad "OB5" smd rect
			(at -1.27762 -28.26004 90)
			(size 0.3556 1.2192)
			(layers "F.Cu" "F.Mask" "F.Paste")
			(net "NIC3_DATA_OUT")
		)
		(pad "OB6" smd rect
			(at -1.27762 -27.660092 90)
			(size 0.3556 1.2192)
			(layers "F.Cu" "F.Mask" "F.Paste")
			(net "NIC3_CLK")
		)
		(pad "OB7" smd rect
			(at -1.27762 -27.05989 90)
			(size 0.3556 1.2192)
			(layers "F.Cu" "F.Mask" "F.Paste")
			(net "NIC3_SLOT_ID0")
		)
		(pad "OB8" smd rect
			(at -1.27762 -26.459942 90)
			(size 0.3556 1.2192)
			(layers "F.Cu" "F.Mask" "F.Paste")
			(net "NCSI_NIC3_RXD1")
		)
		(pad "OB9" smd rect
			(at -1.27762 -25.859994 90)
			(size 0.3556 1.2192)
			(layers "F.Cu" "F.Mask" "F.Paste")
			(net "NCSI_NIC3_RXD0")
		)
		(pad "OB10" smd rect
			(at -1.27762 -25.260046 90)
			(size 0.3556 1.2192)
			(layers "F.Cu" "F.Mask" "F.Paste")
			(net "GND")
		)
		(pad "OB11" smd rect
			(at -1.27762 -24.660098 90)
			(size 0.3556 1.2192)
			(layers "F.Cu" "F.Mask" "F.Paste")
			(net "Net_2615")
		)
		(pad "OB12" smd rect
			(at -1.27762 -24.059896 90)
			(size 0.3556 1.2192)
			(layers "F.Cu" "F.Mask" "F.Paste")
			(net "Net_2618")
		)
		(pad "OB13" smd rect
			(at -1.27762 -23.459948 90)
			(size 0.3556 1.2192)
			(layers "F.Cu" "F.Mask" "F.Paste")
			(net "GND")
		)
		(pad "OB14" smd rect
			(at -1.27762 -22.86 90)
			(size 0.3556 1.2192)
			(layers "F.Cu" "F.Mask" "F.Paste")
			(net "NCSI_NIC3_CRS_DV")
		)
	)
)
